FILE_TYPE = CONNECTIVITY;
{Allegro Design Entry HDL 17.4-2019 S026 (4007227) 1/17/2022}
"PAGE_NUMBER" = 430;
0"NC";
1"GND\g";
2"GND\g";
3"GND\g";
4"GND\g";
5"GND\g";
6"GND\g";
7"P1V8_CPU0_RT_1D\g";
8"GND\g";
9"P1V8_CPU0_RT_1D\g";
10"GND\g";
11"GND\g";
12"P1V8_CPU0_RT_1D\g";
13"GND\g";
14"GND\g";
15"P1V8_CPU0_RT_1D\g";
16"SMB_RT_CPU0_P3_ROM_MUX_1D_SCL";
17"SMB_RT_CPU0_P3_ROM_MUX_1D_R_SCL";
18"SMB_RT_CPU0_P3_ROM_MUX_1D_SDA";
19"SMB_RT_CPU0_P3_ROM_MUX_1D_R_SDA";
20"RT_CPU0_P3_SCAN_MODE";
21"RST_RT_CPU0_P3_PERST_N";
22"RST_RT_CPU0_P3_RESET_N";
23"P1V8_CPU0_RT_1D\g";
24"P1V8_CPU0_RT_1D\g";
25"GND\g";
26"GND\g";
27"P1V8_CPU0_RT_1D\g";
28"CLKREQ_RT_CPU0_P3_N";
29"JTAG_TDO_RT_CPU0_P3";
30"JTAG_TMS_RT_CPU0_P3";
31"JTAG_TDI_RT_CPU0_P3";
32"JTAG_TCK_RT_CPU0_P3";
33"JTAG_TCK_RT_CPU0_P3";
34"JTAG_TRST_RT_CPU0_P3_N";
35"JTAG_TMS_RT_CPU0_P3";
36"GPIO2_RT_CPU0_P3";
37"RXDET_BYP_RT_CPU0_P3";
38"RST_RT_CPU0_P3_RESET_R_N";
39"RST_RT_CPU0_P3_PERST_R_N";
40"RT_CPU0_P3_ADDR2";
41"MODE_RT_CPU0_P3";
42"TEST2_RT_CPU0_P3";
43"GPIO3_RT_CPU0_P3";
44"JTAG_TEST_MODE_RT_CPU0_P3";
45"TEST2_RT_CPU0_P3";
46"GPIO3_RT_CPU0_P3";
47"GPIO2_RT_CPU0_P3";
48"TEST0_RT_CPU0_P3";
49"TEST1_RT_CPU0_P3";
50"SMB_RT_CPU0_P3_R2_SDA";
51"SMB_RT_CPU0_P3_R2_SCL";
52"SMB_RT_CPU0_P3_R_SCL";
53"SMB_RT_CPU0_P3_R_SDA";
54"RT_CPU0_P3_ADDR2";
55"RT_CPU0_P3_ADDR1";
56"RT_CPU0_P3_ADDR3";
57"RT_CPU0_P3_ADDR1";
58"TEST1_RT_CPU0_P3";
59"TEST0_RT_CPU0_P3";
60"RT_CPU0_P3_ADDR3";
61"CLK_100M_RETIMER_CPU0_P3_R_DN";
62"CLK_100M_RETIMER_CPU0_P3_DP";
63"CLK_100M_RETIMER_CPU0_P3_R_DP";
64"CLK_100M_RETIMER_CPU0_P3_DN";
65"JTAG_TDO_RT_CPU0_P3";
66"JTAG_TDI_RT_CPU0_P3";
67"JTAG_TEST_MODE_RT_CPU0_P3";
68"MODE_RT_CPU0_P3";
69"RXDET_BYP_RT_CPU0_P3";
70"RT_CPU0_P3_SCAN_MODE";
71"RST_RT_CPU0_P3_PERST_R_N";
72"RST_RT_CPU0_P3_RESET_R_N";
%"Q_RES"
"2","(-8950,6000)","0","pure_quanta","I10";
;
LOCATION"R1111"
$SEC"1"
CDS_SEC"1"
TOLERANCE"5%"
VALUE"4.7K"
PACK_TYPE"0201LF"
MATERIAL"EMPTY"
WATTAGE"1/20W"
CDS_LIB"pure_quanta"
PART_NUMBER"CS24701JE04";
"A"
$PN"1"23;
"B"
$PN"2"47;
%"UNIVERSAL_GND"
"1","(-1950,2300)","1","pure_quanta_power","I100";
;
CDS_LIB"pure_quanta_power"
HDL_POWER"GND";
"A"1;
%"Q_RES"
"1","(-2675,2300)","0","pure_quanta","I101";
;
LOCATION"R1412"
$SEC"1"
CDS_SEC"1"
VALUE"4.7K"
PACK_TYPE"0201LF"
MATERIAL"CHIP"
WATTAGE"1/20W"
TOLERANCE"5%"
CDS_LIB"pure_quanta"
PART_NUMBER"CS24701JE04";
"B"
$PN"2"1;
"A"
$PN"1"28;
%"Q_RES"
"2","(-8975,3450)","0","pure_quanta","I102";
;
LOCATION"R1106"
$SEC"1"
CDS_SEC"1"
PACK_TYPE"0201LF"
MATERIAL"CHIP"
WATTAGE"1/20W"
TOLERANCE"1%"
VALUE"200"
CDS_LIB"pure_quanta"
PART_NUMBER"CS12001FE12";
"A"
$PN"1"20;
"B"
$PN"2"5;
%"Q_RES"
"2","(-8325,6000)","0","pure_quanta","I11";
;
LOCATION"R1114"
$SEC"1"
CDS_SEC"1"
MATERIAL"EMPTY"
PACK_TYPE"0201LF"
WATTAGE"1/20W"
TOLERANCE"5%"
VALUE"4.7K"
CDS_LIB"pure_quanta"
PART_NUMBER"CS24701JE04";
"A"
$PN"1"23;
"B"
$PN"2"48;
%"Q_RES"
"2","(-1250,1375)","0","pure_quanta","I112";
;
LOCATION"R1482"
$SEC"1"
CDS_SEC"1"
PACK_TYPE"0201LF"
MATERIAL"EMPTY"
WATTAGE"1/20W"
TOLERANCE"5%"
VALUE"4.7K"
CDS_LIB"pure_quanta"
PART_NUMBER"CS24701JE04";
"A"
$PN"1"24;
"B"
$PN"2"31;
%"Q_RES"
"2","(-975,1375)","0","pure_quanta","I113";
;
LOCATION"R1483"
$SEC"1"
CDS_SEC"1"
PACK_TYPE"0201LF"
VALUE"4.7K"
MATERIAL"EMPTY"
TOLERANCE"5%"
WATTAGE"1/20W"
CDS_LIB"pure_quanta"
PART_NUMBER"CS24701JE04";
"A"
$PN"1"24;
"B"
$PN"2"30;
%"GND"
"1","(-425,450)","0","pure_quanta_power","I115";
;
SIZE"1B"
BOM_COST"MEM"
CDS_LIB"pure_quanta_power"
HDL_POWER"GND";
"A<SIZE-1..0>\NAC"2;
%"Q_RES"
"2","(-425,750)","0","pure_quanta","I117";
;
LOCATION"R1409"
$SEC"1"
CDS_SEC"1"
PACK_TYPE"0201LF"
MATERIAL"CHIP"
WATTAGE"1/20W"
VALUE"4.7K"
TOLERANCE"5%"
CDS_LIB"pure_quanta"
PART_NUMBER"CS24701JE04";
"A"
$PN"1"32;
"B"
$PN"2"2;
%"Q_RES"
"2","(-700,1375)","0","pure_quanta","I118";
;
LOCATION"R1484"
$SEC"1"
CDS_SEC"1"
VALUE"1K"
TOLERANCE"1%"
WATTAGE"1/20W"
PACK_TYPE"0201LF"
MATERIAL"EMPTY"
CDS_LIB"pure_quanta"
PART_NUMBER"CS21001FE07";
"A"
$PN"1"24;
"B"
$PN"2"29;
%"Q_RES"
"2","(-425,1400)","0","pure_quanta","I119";
;
LOCATION"R1485"
$SEC"1"
CDS_SEC"1"
WATTAGE"1/20W"
MATERIAL"EMPTY"
TOLERANCE"5%"
PACK_TYPE"0201LF"
VALUE"4.7K"
CDS_LIB"pure_quanta"
PART_NUMBER"CS24701JE04";
"A"
$PN"1"24;
"B"
$PN"2"32;
%"P1V0"
"1","(-8950,6400)","0","pure_quanta_power","I12";
;
HDL_POWER"P1V8_CPU0_RT_1D"
CDS_LIB"pure_quanta_power";
"A"23;
%"P1V0"
"1","(-425,1700)","0","pure_quanta_power","I120";
;
HDL_POWER"P1V8_CPU0_RT_1D"
CDS_LIB"pure_quanta_power";
"A"24;
%"Q_RES"
"1","(-6600,1050)","0","pure_quanta","I15";
;
LOCATION"R616"
SEC"1"
MATERIAL"CHIP"
PACK_TYPE"0201LF"
CDS_LIB"pure_quanta"
TOLERANCE"5%"
VALUE"0"
WATTAGE"1/20W"
SEC_TYPE"0201LF"
PART_NUMBER"CS00001JE10";
"B"
$PN"2"64;
"A"
$PN"1"61;
%"UNIVERSAL_GND"
"1","(-6300,400)","0","pure_quanta_power","I16";
;
CDS_LIB"pure_quanta_power"
HDL_POWER"GND";
"A"3;
%"UNIVERSAL_GND"
"1","(-6150,400)","0","pure_quanta_power","I17";
;
CDS_LIB"pure_quanta_power"
HDL_POWER"GND";
"A"4;
%"Q_RES"
"2","(-6300,725)","2","pure_quanta","I18";
;
LOCATION"R635"
$SEC"1"
CDS_SEC"1"
TOLERANCE"1%"
PACK_TYPE"0201LF"
VALUE"51.1"
MATERIAL"EMPTY"
WATTAGE"1/20W"
CDS_LIB"pure_quanta"
PART_NUMBER"CS05111FE00";
"A"
$PN"1"64;
"B"
$PN"2"3;
%"Q_RES"
"2","(-6150,725)","0","pure_quanta","I19";
;
LOCATION"R636"
$SEC"1"
CDS_SEC"1"
WATTAGE"1/20W"
PACK_TYPE"0201LF"
MATERIAL"EMPTY"
VALUE"51.1"
TOLERANCE"1%"
CDS_LIB"pure_quanta"
PART_NUMBER"CS05111FE00";
"A"
$PN"1"62;
"B"
$PN"2"4;
%"Q_RES"
"1","(-6600,1200)","0","pure_quanta","I20";
;
LOCATION"R615"
SEC"1"
MATERIAL"CHIP"
TOLERANCE"5%"
PACK_TYPE"0201LF"
WATTAGE"1/20W"
VALUE"0"
CDS_LIB"pure_quanta"
SEC_TYPE"0201LF"
PART_NUMBER"CS00001JE10";
"B"
$PN"2"62;
"A"
$PN"1"63;
%"Q_RES"
"1","(-6325,1550)","0","pure_quanta","I21";
;
LOCATION"R686"
$SEC"1"
CDS_SEC"1"
CDS_LIB"pure_quanta"
MATERIAL"CHIP"
WATTAGE"1/20W"
PACK_TYPE"0201LF"
VALUE"49.9"
TOLERANCE"1%"
PART_NUMBER"CS04991FE06";
"B"
$PN"2"19;
"A"
$PN"1"18;
%"Q_RES"
"1","(-6325,1650)","0","pure_quanta","I22";
;
LOCATION"R684"
$SEC"1"
CDS_SEC"1"
PACK_TYPE"0201LF"
MATERIAL"CHIP"
WATTAGE"1/20W"
VALUE"49.9"
TOLERANCE"1%"
CDS_LIB"pure_quanta"
PART_NUMBER"CS04991FE06";
"B"
$PN"2"17;
"A"
$PN"1"16;
%"UNIVERSAL_GND"
"1","(-8975,3175)","0","pure_quanta_power","I3";
;
CDS_LIB"pure_quanta_power"
HDL_POWER"GND";
"A"5;
%"Q_RES"
"1","(-6350,2900)","0","pure_quanta","I32";
;
LOCATION"R1109"
$SEC"1"
CDS_SEC"1"
VALUE"0"
PACK_TYPE"0201LF"
WATTAGE"1/20W"
MATERIAL"CHIP"
TOLERANCE"5%"
CDS_LIB"pure_quanta"
PART_NUMBER"CS00001JE10";
"B"
$PN"2"51;
"A"
$PN"1"52;
%"Q_RES"
"1","(-6350,2800)","0","pure_quanta","I33";
;
LOCATION"R1110"
$SEC"1"
CDS_SEC"1"
CDS_LIB"pure_quanta"
PACK_TYPE"0201LF"
MATERIAL"CHIP"
TOLERANCE"5%"
VALUE"0"
WATTAGE"1/20W"
PART_NUMBER"CS00001JE10";
"B"
$PN"2"50;
"A"
$PN"1"53;
%"Q_RES"
"2","(-8025,5025)","0","pure_quanta","I36";
;
LOCATION"R1118"
$SEC"1"
CDS_SEC"1"
TOLERANCE"5%"
VALUE"4.7K"
PACK_TYPE"0201LF"
WATTAGE"1/20W"
MATERIAL"CHIP"
CDS_LIB"pure_quanta"
PART_NUMBER"CS24701JE04";
"A"
$PN"1"49;
"B"
$PN"2"25;
%"Q_RES"
"2","(-7725,5025)","0","pure_quanta","I37";
;
LOCATION"R1120"
$SEC"1"
CDS_SEC"1"
MATERIAL"CHIP"
VALUE"4.7K"
TOLERANCE"5%"
WATTAGE"1/20W"
PACK_TYPE"0201LF"
CDS_LIB"pure_quanta"
PART_NUMBER"CS24701JE04";
"A"
$PN"1"42;
"B"
$PN"2"25;
%"UNIVERSAL_GND"
"1","(-7425,4550)","0","pure_quanta_power","I38";
;
CDS_LIB"pure_quanta_power"
HDL_POWER"GND";
"A"25;
%"Q_RES"
"2","(-7425,5000)","0","pure_quanta","I39";
;
LOCATION"R1121"
$SEC"1"
CDS_SEC"1"
VALUE"4.7K"
TOLERANCE"5%"
WATTAGE"1/20W"
MATERIAL"CHIP"
PACK_TYPE"0201LF"
CDS_LIB"pure_quanta"
PART_NUMBER"CS24701JE04";
"A"
$PN"1"44;
"B"
$PN"2"25;
%"Q_RES"
"2","(-8025,5950)","0","pure_quanta","I40";
;
LOCATION"R1116"
$SEC"1"
CDS_SEC"1"
TOLERANCE"5%"
PACK_TYPE"0201LF"
MATERIAL"EMPTY"
WATTAGE"1/20W"
VALUE"4.7K"
CDS_LIB"pure_quanta"
PART_NUMBER"CS24701JE04";
"A"
$PN"1"23;
"B"
$PN"2"49;
%"Q_RES"
"2","(-7725,5975)","0","pure_quanta","I41";
;
LOCATION"R1119"
$SEC"1"
CDS_SEC"1"
WATTAGE"1/20W"
MATERIAL"EMPTY"
TOLERANCE"5%"
PACK_TYPE"0201LF"
VALUE"4.7K"
CDS_LIB"pure_quanta"
PART_NUMBER"CS24701JE04";
"A"
$PN"1"23;
"B"
$PN"2"42;
%"Q_RES"
"2","(-7425,6000)","0","pure_quanta","I42";
;
LOCATION"R1108"
$SEC"1"
CDS_SEC"1"
MATERIAL"EMPTY"
WATTAGE"1/20W"
TOLERANCE"5%"
PACK_TYPE"0201LF"
VALUE"4.7K"
CDS_LIB"pure_quanta"
PART_NUMBER"CS24701JE04";
"A"
$PN"1"23;
"B"
$PN"2"44;
%"UNIVERSAL_GND"
"1","(-5025,5200)","0","pure_quanta_power","I49";
;
CDS_LIB"pure_quanta_power"
HDL_POWER"GND";
"A"6;
%"Q_RES"
"2","(-8975,4125)","0","pure_quanta","I5";
;
LOCATION"R1105"
$SEC"1"
CDS_SEC"1"
MATERIAL"EMPTY"
VALUE"4.7K"
TOLERANCE"5%"
WATTAGE"1/20W"
PACK_TYPE"0201LF"
CDS_LIB"pure_quanta"
PART_NUMBER"CS24701JE04";
"A"
$PN"1"9;
"B"
$PN"2"20;
%"Q_RES"
"2","(-5025,5550)","0","pure_quanta","I50";
;
LOCATION"R1091"
$SEC"1"
CDS_SEC"1"
PACK_TYPE"0201LF"
MATERIAL"EMPTY"
WATTAGE"1/20W"
TOLERANCE"5%"
VALUE"4.7K"
CDS_LIB"pure_quanta"
PART_NUMBER"CS24701JE04";
"A"
$PN"1"41;
"B"
$PN"2"6;
%"Q_RES"
"2","(-5025,6075)","0","pure_quanta","I51";
;
LOCATION"R1122"
$SEC"1"
CDS_SEC"1"
PACK_TYPE"0201LF"
WATTAGE"1/20W"
TOLERANCE"5%"
MATERIAL"CHIP"
VALUE"4.7K"
CDS_LIB"pure_quanta"
PART_NUMBER"CS24701JE04";
"A"
$PN"1"7;
"B"
$PN"2"41;
%"P1V0"
"1","(-5025,6400)","0","pure_quanta_power","I53";
;
HDL_POWER"P1V8_CPU0_RT_1D"
CDS_LIB"pure_quanta_power";
"A"7;
%"UNIVERSAL_GND"
"1","(-2625,1700)","1","pure_quanta_power","I54";
;
CDS_LIB"pure_quanta_power"
HDL_POWER"GND";
"A"8;
%"Q_RES"
"1","(-2575,2100)","0","pure_quanta","I55";
;
LOCATION"R1096"
$SEC"1"
CDS_SEC"1"
PACK_TYPE"0201LF"
VALUE"0"
CDS_LIB"pure_quanta"
MATERIAL"CHIP"
TOLERANCE"5%"
WATTAGE"1/20W"
PART_NUMBER"CS00001JE10";
"B"
$PN"2"72;
"A"
$PN"1"22;
%"Q_RES"
"1","(-2575,2200)","0","pure_quanta","I56";
;
LOCATION"R1088"
SEC"1"
PACK_TYPE"0201LF"
VALUE"0"
WATTAGE"1/20W"
TOLERANCE"5%"
MATERIAL"CHIP"
SEC_TYPE"0201LF"
CDS_LIB"pure_quanta"
PART_NUMBER"CS00001JE10";
"B"
$PN"2"71;
"A"
$PN"1"21;
%"P1V0"
"1","(-8975,4450)","0","pure_quanta_power","I6";
;
HDL_POWER"P1V8_CPU0_RT_1D"
CDS_LIB"pure_quanta_power";
"A"9;
%"UNIVERSAL_GND"
"1","(-3475,4800)","0","pure_quanta_power","I64";
;
CDS_LIB"pure_quanta_power"
HDL_POWER"GND";
"A"26;
%"Q_RES"
"2","(-3475,5225)","0","pure_quanta","I65";
;
LOCATION"R1098"
$SEC"1"
CDS_SEC"1"
MATERIAL"EMPTY"
WATTAGE"1/20W"
PACK_TYPE"0201LF"
VALUE"1K"
TOLERANCE"1%"
CDS_LIB"pure_quanta"
PART_NUMBER"CS21001FE07";
"A"
$PN"1"56;
"B"
$PN"2"26;
%"Q_RES"
"2","(-3175,5225)","0","pure_quanta","I66";
;
LOCATION"R1100"
$SEC"1"
CDS_SEC"1"
MATERIAL"CHIP"
WATTAGE"1/20W"
VALUE"20K"
TOLERANCE"1%"
PACK_TYPE"0201LF"
CDS_LIB"pure_quanta"
PART_NUMBER"CS32001FE00";
"A"
$PN"1"40;
"B"
$PN"2"26;
%"Q_RES"
"2","(-3475,6000)","0","pure_quanta","I67";
;
LOCATION"R1097"
$SEC"1"
CDS_SEC"1"
VALUE"1K"
PACK_TYPE"0201LF"
MATERIAL"CHIP"
WATTAGE"1/20W"
TOLERANCE"1%"
CDS_LIB"pure_quanta"
PART_NUMBER"CS21001FE07";
"A"
$PN"1"27;
"B"
$PN"2"56;
%"Q_RES"
"2","(-3175,6000)","0","pure_quanta","I68";
;
LOCATION"R1099"
$SEC"1"
CDS_SEC"1"
TOLERANCE"1%"
VALUE"1K"
WATTAGE"1/20W"
PACK_TYPE"0201LF"
MATERIAL"EMPTY"
CDS_LIB"pure_quanta"
PART_NUMBER"CS21001FE07";
"A"
$PN"1"27;
"B"
$PN"2"40;
%"Q_RES"
"2","(-2825,5225)","0","pure_quanta","I69";
;
LOCATION"R1102"
$SEC"1"
CDS_SEC"1"
PACK_TYPE"0201LF"
WATTAGE"1/20W"
TOLERANCE"1%"
VALUE"1K"
MATERIAL"CHIP"
CDS_LIB"pure_quanta"
PART_NUMBER"CS21001FE07";
"A"
$PN"1"57;
"B"
$PN"2"26;
%"Q_RES"
"2","(-8950,5050)","0","pure_quanta","I7";
;
LOCATION"R1112"
$SEC"1"
CDS_SEC"1"
VALUE"10K"
TOLERANCE"1%"
WATTAGE"1/20W"
MATERIAL"CHIP"
PACK_TYPE"0201LF"
CDS_LIB"pure_quanta"
PART_NUMBER"CS31001FE17";
"A"
$PN"1"47;
"B"
$PN"2"25;
%"Q_RES"
"2","(-2825,5975)","0","pure_quanta","I70";
;
LOCATION"R1101"
$SEC"1"
CDS_SEC"1"
WATTAGE"1/20W"
TOLERANCE"1%"
PACK_TYPE"0201LF"
VALUE"1K"
MATERIAL"EMPTY"
CDS_LIB"pure_quanta"
PART_NUMBER"CS21001FE07";
"A"
$PN"1"27;
"B"
$PN"2"57;
%"P1V0"
"1","(-3475,6425)","0","pure_quanta_power","I71";
;
HDL_POWER"P1V8_CPU0_RT_1D"
CDS_LIB"pure_quanta_power";
"A"27;
%"GND"
"1","(-1475,4850)","0","pure_quanta_power","I72";
;
BOM_COST"MEM"
SIZE"1B"
CDS_LIB"pure_quanta_power"
HDL_POWER"GND";
"A<SIZE-1..0>\NAC"10;
%"GND"
"1","(-1300,4875)","0","pure_quanta_power","I73";
;
CDS_LIB"pure_quanta_power"
BOM_COST"MEM"
SIZE"1B"
HDL_POWER"GND";
"A<SIZE-1..0>\NAC"11;
%"Q_RES"
"2","(-1300,5225)","0","pure_quanta","I74";
;
LOCATION"R1103"
$SEC"1"
CDS_SEC"1"
VALUE"10K"
TOLERANCE"1%"
WATTAGE"1/20W"
MATERIAL"CHIP"
PACK_TYPE"0201LF"
CDS_LIB"pure_quanta"
PART_NUMBER"CS31001FE17";
"A"
$PN"1"39;
"B"
$PN"2"11;
%"Q_RES"
"2","(-1475,5225)","2","pure_quanta","I75";
;
LOCATION"R1104"
$SEC"1"
CDS_SEC"1"
TOLERANCE"1%"
WATTAGE"1/20W"
VALUE"10K"
MATERIAL"CHIP"
PACK_TYPE"0201LF"
CDS_LIB"pure_quanta"
PART_NUMBER"CS31001FE17";
"A"
$PN"1"38;
"B"
$PN"2"10;
%"Q_RES"
"2","(-1475,6050)","2","pure_quanta","I79";
;
LOCATION"R1107"
$SEC"1"
CDS_SEC"1"
PACK_TYPE"0201LF"
MATERIAL"EMPTY"
VALUE"4.7K"
TOLERANCE"5%"
WATTAGE"1/20W"
CDS_LIB"pure_quanta"
PART_NUMBER"CS24701JE04";
"A"
$PN"1"12;
"B"
$PN"2"38;
%"Q_RES"
"2","(-8650,5050)","0","pure_quanta","I8";
;
LOCATION"R1113"
$SEC"1"
CDS_SEC"1"
WATTAGE"1/20W"
MATERIAL"CHIP"
TOLERANCE"1%"
VALUE"10K"
PACK_TYPE"0201LF"
CDS_LIB"pure_quanta"
PART_NUMBER"CS31001FE17";
"A"
$PN"1"46;
"B"
$PN"2"25;
%"P1V0"
"1","(-1475,6300)","0","pure_quanta_power","I82";
;
HDL_POWER"P1V8_CPU0_RT_1D"
CDS_LIB"pure_quanta_power";
"A"12;
%"PT5161LRS"
"3","(-4375,2350)","0","pure_quanta","I83";
;
LOCATION"U6013"
$SEC"3"
CDS_SEC"3"
PART_TYPE"SMLF"
MATERIAL"IC"
VALUE"PT5161LRS"
NEEDS_NO_SIZE"TRUE"
CDS_LMAN_SYM_OUTLINE"-500,1450,450,-1400"
CDS_LIB"pure_quanta"
PART_NUMBER"AJ051610U03";
"EE_DAT"
$PN"FJ3"19;
"EE_CLK"
$PN"FF5"17;
"CLKREQ_N \B"
$PN"G35"28;
"TEST2"
$PN"FF30"45;
"TEST1"
$PN"FF27"58;
"TEST0"
$PN"FF24"59;
"T_SENSE"
$PN"E30"8;
"SMBDAT"
$PN"B28"50;
"SMBCLK"
$PN"B31"51;
"SMB_ADDR3"
$PN"B25"60;
"SMB_ADDR2"
$PN"B23"54;
"SMB_ADDR1"
$PN"F34"55;
"SCAN_MODE"
$PN"FF33"70;
"RXDET_BYP"
$PN"E11"69;
"RESET_N \B"
$PN"FF11"22;
"REFCLKP"
$PN"FJ16"62;
"REFCLKN"
$PN"FF18"64;
"REFCLK_OUTP"
$PN"B16"0;
"REFCLK_OUTN"
$PN"E18"0;
"PERST_N \B"
$PN"F2"21;
"MODE"
$PN"FJ9"68;
"JTAG_TRST_N \B"
$PN"E8"34;
"JTAG_TMS"
$PN"B12"35;
"JTAG_TEST_MODE"
$PN"FF8"67;
"JTAG_TDO"
$PN"B9"65;
"JTAG_TDI"
$PN"B6"66;
"JTAG_TCK"
$PN"B3"33;
"INT_N \B"
$PN"FJ31"0;
"GPIO3"
$PN"FJ28"43;
"GPIO2"
$PN"FJ25"36;
"GPIO1"
$PN"FJ23"0;
"GPIO0"
$PN"FJ6"0;
%"Q_RES"
"1","(-2700,3250)","0","pure_quanta","I85";
;
LOCATION"R1408"
$SEC"1"
CDS_SEC"1"
MATERIAL"CHIP"
VALUE"1K"
PACK_TYPE"0201LF"
TOLERANCE"1%"
WATTAGE"1/20W"
CDS_LIB"pure_quanta"
PART_NUMBER"CS21001FE07";
"B"
$PN"2"13;
"A"
$PN"1"34;
%"Q_RES"
"2","(-8325,5050)","0","pure_quanta","I9";
;
LOCATION"R1115"
$SEC"1"
CDS_SEC"1"
MATERIAL"CHIP"
WATTAGE"1/20W"
VALUE"4.7K"
TOLERANCE"5%"
PACK_TYPE"0201LF"
CDS_LIB"pure_quanta"
PART_NUMBER"CS24701JE04";
"A"
$PN"1"48;
"B"
$PN"2"25;
%"UNIVERSAL_GND"
"1","(-1950,3250)","1","pure_quanta_power","I92";
;
CDS_LIB"pure_quanta_power"
HDL_POWER"GND";
"A"13;
%"GND"
"1","(-1325,2850)","0","pure_quanta_power","I95";
;
BOM_COST"MEM"
SIZE"1B"
CDS_LIB"pure_quanta_power"
HDL_POWER"GND";
"A<SIZE-1..0>\NAC"14;
%"Q_RES"
"2","(-1325,3250)","0","pure_quanta","I96";
;
LOCATION"R1414"
$SEC"1"
CDS_SEC"1"
WATTAGE"1/20W"
VALUE"10K"
PACK_TYPE"0201LF"
TOLERANCE"1%"
MATERIAL"CHIP"
CDS_LIB"pure_quanta"
PART_NUMBER"CS31001FE17";
"A"
$PN"1"37;
"B"
$PN"2"14;
%"Q_RES"
"2","(-1325,3775)","0","pure_quanta","I97";
;
LOCATION"R1413"
$SEC"1"
CDS_SEC"1"
PACK_TYPE"0201LF"
TOLERANCE"1%"
WATTAGE"1/20W"
MATERIAL"EMPTY"
VALUE"1K"
CDS_LIB"pure_quanta"
PART_NUMBER"CS21001FE07";
"A"
$PN"1"15;
"B"
$PN"2"37;
%"P1V0"
"1","(-1325,4175)","0","pure_quanta_power","I98";
;
HDL_POWER"P1V8_CPU0_RT_1D"
CDS_LIB"pure_quanta_power";
"A"15;
END.
